# BASEBOARD_FAB2 (Tioga Pass) — schematic netlist excerpt (pin names and nets, part order shuffled) for the footprints in the layout excerpt that follows; sources: Cadence DE-HDL packaged netlist, KiCad conversion of Wiwynn_Tioga_Pass_MB.brd

Q7E2  FET_N_DUAL  NTJD4001N FET  pkg SMLF  page 94
  SOURCE(0)  = GND
  GATE(0)  = IRQ_PVDDQ_GHJ_VRHOT_LVT3_N
  DRAIN(0)  = H_CPU1_MEMGHJ_MEMHOT_G_N
  SOURCE(0)  = GND
  GATE(0)  = H_CPU1_MEMGHJ_MEMHOT
  DRAIN(0)  = H_CPU1_MEMGHJ_MEMHOT

R1T40  RES  49.9 1% CHIP  pkg 0402  page 151 : A = BMC_M_CLK_DP ; B = BMC_M_CLK

(kicad_pcb
	(version 20260206)
	(generator "pcbnew")
	(generator_version "10.0")
	(general
		(thickness 1.6)
		(legacy_teardrops no)
	)
	(paper "A4")
	(title_block
		(title "Wiwynn_Tioga_Pass_MB.brd")
		(comment 1 "Tioga Pass / footprints 4396-4397 of 4770")
	)
	(layers
		(0 "F.Cu" signal "TOP")
		(4 "In1.Cu" signal "L2GND")
		(6 "In2.Cu" signal "L3")
		(8 "In3.Cu" signal "L4GND")
		(10 "In4.Cu" signal "L5")
		(12 "In5.Cu" signal "L6GND")
		(14 "In6.Cu" signal "L7VCC")
		(16 "In7.Cu" signal "L8VCC")
		(18 "In8.Cu" signal "L9GND")
		(20 "In9.Cu" signal "L10")
		(22 "In10.Cu" signal "L11GND")
		(24 "In11.Cu" signal "L12")
		(26 "In12.Cu" signal "L13GND")
		(2 "B.Cu" signal "BOTTOM")
		(9 "F.Adhes" user "F.Adhesive")
		(11 "B.Adhes" user "B.Adhesive")
		(13 "F.Paste" user "Package Geometry/Pastemask Top")
		(15 "B.Paste" user "Package Geometry/Pastemask Bottom")
		(5 "F.SilkS" user "Ref Des/Silkscreen Top")
		(7 "B.SilkS" user "Ref Des/Silkscreen Bottom")
		(1 "F.Mask" user "Board Geometry/Soldermask Top")
		(3 "B.Mask" user "Board Geometry/Soldermask Bottom")
		(17 "Dwgs.User" user "User.Drawings")
		(19 "Cmts.User" user "User.Comments")
		(21 "Eco1.User" user "User.Eco1")
		(23 "Eco2.User" user "User.Eco2")
		(25 "Edge.Cuts" user "Board Geometry/Outline")
		(27 "Margin" user)
		(31 "F.CrtYd" user "Package Geometry/Place Bound Top")
		(29 "B.CrtYd" user "Package Geometry/Place Bound Bottom")
		(35 "F.Fab" user "Ref Des/Assembly Top")
		(33 "B.Fab" user "Ref Des/Assembly Bottom")
	)
	(footprint ""
		(layer "B.Cu")
		(at 409.884118 -87.526114 180)
		(property "Reference" "Q7E2"
			(at 1.20777 1.88214 90)
			(unlocked yes)
			(layer "B.SilkS")
			(effects
				(font
					(size 0.7874 0.5842)
					(thickness 0.1524)
				)
				(justify left mirror)
			)
		)
		(property "Value" ""
			(at 0 0 0)
			(layer "B.Fab")
			(effects
				(font
					(size 1.27 1.27)
				)
				(justify mirror)
			)
		)
		(duplicate_pad_numbers_are_jumpers no)
		(fp_circle
			(center 0.508 -0.7874)
			(end 0.381 -0.7874)
			(stroke
				(width 0.254)
				(type default)
			)
			(fill no)
			(layer "B.SilkS")
		)
		(fp_poly
			(pts
				(xy -0.2159 1.7526) (xy -1.5621 1.7526) (xy -1.5621 -0.4572) (xy -0.2159 -0.4572)
			)
			(stroke
				(width 0)
				(type default)
			)
			(fill no)
			(layer "B.CrtYd")
		)
		(fp_line
			(start -0.2159 1.75514)
			(end -1.5621 1.75514)
			(stroke
				(width 0.1)
				(type default)
			)
			(layer "B.Fab")
		)
		(fp_line
			(start -0.2159 -0.45466)
			(end -0.2159 1.75514)
			(stroke
				(width 0.1)
				(type default)
			)
			(layer "B.Fab")
		)
		(fp_line
			(start -1.5621 1.75514)
			(end -1.5621 -0.45466)
			(stroke
				(width 0.1)
				(type default)
			)
			(layer "B.Fab")
		)
		(fp_line
			(start -1.5621 -0.45466)
			(end -0.2159 -0.45466)
			(stroke
				(width 0.1)
				(type default)
			)
			(layer "B.Fab")
		)
		(fp_circle
			(center 0.508 -0.7874)
			(end 0.381 -0.7874)
			(stroke
				(width 0.254)
				(type default)
			)
			(fill no)
			(layer "B.Fab")
		)
		(pad "1" smd rect
			(at 0 0)
			(size 1.016 0.381)
			(layers "B.Cu" "B.Mask" "B.Paste")
			(net "GND")
		)
		(pad "2" smd rect
			(at 0 0.65024)
			(size 1.016 0.381)
			(layers "B.Cu" "B.Mask" "B.Paste")
			(net "IRQ_PVDDQ_GHJ_VRHOT_LVT3_N")
		)
		(pad "3" smd rect
			(at 0 1.30048)
			(size 1.016 0.381)
			(layers "B.Cu" "B.Mask" "B.Paste")
			(net "H_CPU1_MEMGHJ_MEMHOT_G_N")
		)
		(pad "4" smd rect
			(at -1.778 1.30048)
			(size 1.016 0.381)
			(layers "B.Cu" "B.Mask" "B.Paste")
			(net "GND")
		)
		(pad "5" smd rect
			(at -1.778 0.65024)
			(size 1.016 0.381)
			(layers "B.Cu" "B.Mask" "B.Paste")
			(net "H_CPU1_MEMGHJ_MEMHOT")
		)
		(pad "6" smd rect
			(at -1.778 0)
			(size 1.016 0.381)
			(layers "B.Cu" "B.Mask" "B.Paste")
			(net "H_CPU1_MEMGHJ_MEMHOT")
		)
		(zone
			(layer "B.Cu")
			(hatch none 0.5)
			(connect_pads
				(clearance 0)
			)
			(min_thickness 0.25)
			(keepout
				(tracks allowed)
				(vias not_allowed)
				(pads allowed)
				(copperpour not_allowed)
				(footprints allowed)
			)
			(placement
				(enabled no)
				(sheetname "")
			)
			(fill
				(thermal_gap 0.5)
				(thermal_bridge_width 0.5)
				(island_removal_mode 0)
			)
			(polygon
				(pts
					(xy 409.376118 -87.335614) (xy 410.392118 -87.335614) (xy 410.392118 -89.024714) (xy 409.376118 -89.024714)
				)
			)
		)
		(zone
			(layer "B.Cu")
			(hatch none 0.5)
			(connect_pads
				(clearance 0)
			)
			(min_thickness 0.25)
			(keepout
				(tracks allowed)
				(vias not_allowed)
				(pads allowed)
				(copperpour not_allowed)
				(footprints allowed)
			)
			(placement
				(enabled no)
				(sheetname "")
			)
			(fill
				(thermal_gap 0.5)
				(thermal_bridge_width 0.5)
				(island_removal_mode 0)
			)
			(polygon
				(pts
					(xy 411.154118 -87.335614) (xy 412.170118 -87.335614) (xy 412.170118 -89.024714) (xy 411.154118 -89.024714)
				)
			)
		)
	)
	(footprint ""
		(layer "B.Cu")
		(at 438.604406 -32.100774 90)
		(property "Reference" "R1T40"
			(at 0.8382 -0.67818 90)
			(unlocked yes)
			(layer "B.SilkS")
			(effects
				(font
					(size 0.4064 0.254)
					(thickness 0.1524)
				)
				(justify left mirror)
			)
		)
		(property "Value" ""
			(at 0 0 90)
			(layer "B.Fab")
			(effects
				(font
					(size 1.27 1.27)
				)
				(justify mirror)
			)
		)
		(duplicate_pad_numbers_are_jumpers no)
		(fp_poly
			(pts
				(xy 0.2794 -0.1016) (xy -0.2794 -0.1016) (xy -0.2794 0.9906) (xy 0.2794 0.9906)
			)
			(stroke
				(width 0)
				(type default)
			)
			(fill no)
			(layer "B.CrtYd")
		)
		(fp_line
			(start 0.2794 -0.1016)
			(end 0.2794 0.9906)
			(stroke
				(width 0.1)
				(type default)
			)
			(layer "B.Fab")
		)
		(fp_line
			(start -0.2794 -0.1016)
			(end 0.2794 -0.1016)
			(stroke
				(width 0.1)
				(type default)
			)
			(layer "B.Fab")
		)
		(fp_line
			(start 0.2794 0.9906)
			(end -0.2794 0.9906)
			(stroke
				(width 0.1)
				(type default)
			)
			(layer "B.Fab")
		)
		(fp_line
			(start -0.2794 0.9906)
			(end -0.2794 -0.1016)
			(stroke
				(width 0.1)
				(type default)
			)
			(layer "B.Fab")
		)
		(pad "1" smd rect
			(at 0 0 270)
			(size 0.508 0.508)
			(layers "B.Cu" "B.Mask" "B.Paste")
			(net "BMC_M_CLK_DP")
		)
		(pad "2" smd rect
			(at 0 0.889 270)
			(size 0.508 0.508)
			(layers "B.Cu" "B.Mask" "B.Paste")
			(net "BMC_M_CLK")
		)
		(zone
			(layer "B.Cu")
			(hatch none 0.5)
			(connect_pads
				(clearance 0)
			)
			(min_thickness 0.25)
			(keepout
				(tracks allowed)
				(vias not_allowed)
				(pads allowed)
				(copperpour not_allowed)
				(footprints allowed)
			)
			(placement
				(enabled no)
				(sheetname "")
			)
			(fill
				(thermal_gap 0.5)
				(thermal_bridge_width 0.5)
				(island_removal_mode 0)
			)
			(polygon
				(pts
					(xy 438.858406 -32.354774) (xy 438.858406 -31.846774) (xy 439.239406 -31.846774) (xy 439.239406 -32.354774)
				)
			)
		)
		(zone
			(layer "B.Cu")
			(hatch none 0.5)
			(connect_pads
				(clearance 0)
			)
			(min_thickness 0.25)
			(keepout
				(tracks not_allowed)
				(vias allowed)
				(pads allowed)
				(copperpour not_allowed)
				(footprints allowed)
			)
			(placement
				(enabled no)
				(sheetname "")
			)
			(fill
				(thermal_gap 0.5)
				(thermal_bridge_width 0.5)
				(island_removal_mode 0)
			)
			(polygon
				(pts
					(xy 439.239406 -32.354774) (xy 439.239406 -31.846774) (xy 438.858406 -31.846774) (xy 438.858406 -32.354774)
				)
			)
		)
	)
)
